G04 ================== begin FILE IDENTIFICATION RECORD ==================*
G04 Layout Name:  15669-1.brd*
G04 Film Name:    SE_REF_L6*
G04 File Format:  Gerber RS274X*
G04 File Origin:  Cadence Allegro 16.5-S056*
G04 Origin Date:  Wed Nov 16 04:09:26 2016*
G04 *
G04 Layer:  BOARD GEOMETRY/SE_REF_L6_TBL*
G04 Layer:  BOARD GEOMETRY/SE_REF_L6_L6*
G04 Layer:  BOARD GEOMETRY/PANEL_OUTLINE*
G04 *
G04 Offset:    (0.00 0.00)*
G04 Mirror:    No*
G04 Mode:      Positive*
G04 Rotation:  0*
G04 FullContactRelief:  No*
G04 UndefLineWidth:     6.00*
G04 ================== end FILE IDENTIFICATION RECORD ====================*
%FSLAX35Y35*MOIN*%
%IR0*IPPOS*OFA0.00000B0.00000*MIA0B0*SFA1.00000B1.00000*%
%ADD10C,.02*%
%ADD11C,.006*%
G75*
%LPD*%
G75*
G54D10*
G01X1178253Y1923126D02*
X1895753D01*
G01X1178253Y1888476D02*
X1895753D01*
G01X1178253Y1957776D02*
Y1888476D01*
G01Y1957776D02*
X1895753D01*
G01X1353253D02*
Y1888476D01*
G01X1580753Y1957776D02*
Y1888476D01*
G01X1685753Y1957776D02*
Y1888476D01*
G01X1895753Y1957776D02*
Y1888476D01*
G54D11*
G01X-84302Y-32800D02*
Y-50300D01*
G01X-89324Y-32800D02*
X-79280D01*
G01X-70514Y-50300D02*
Y-32800D01*
G01Y-41258D02*
X-69422Y-39800D01*
X-68330Y-38925D01*
X-66584Y-38634D01*
X-65274Y-38925D01*
X-63745Y-40092D01*
X-63090Y-41842D01*
Y-50300D01*
G01X-49302Y-38634D02*
Y-50300D01*
G01Y-33967D02*
X-49739Y-33675D01*
Y-33092D01*
X-49302Y-32800D01*
X-48865Y-33092D01*
Y-33675D01*
X-49302Y-33967D01*
G01X-35077Y-48259D02*
X-33985Y-49425D01*
X-32457Y-50300D01*
X-31147D01*
X-29837Y-49717D01*
X-28964Y-48842D01*
X-28527Y-47676D01*
X-28745Y-45925D01*
X-29619Y-45050D01*
X-33549Y-43300D01*
X-34422Y-41258D01*
X-33985Y-39800D01*
X-33112Y-38925D01*
X-31802Y-38634D01*
X-30492Y-38925D01*
X-29182Y-39800D01*
G01X141Y-54675D02*
X1670Y-55842D01*
X3416Y-56133D01*
X4944Y-55842D01*
X6255Y-54384D01*
X7128Y-52342D01*
Y-38634D01*
G01Y-40967D02*
X6255Y-39800D01*
X4944Y-38925D01*
X3416Y-38634D01*
X1670Y-39217D01*
X578Y-40383D01*
X-296Y-42425D01*
X-732Y-44467D01*
X-514Y-46217D01*
X360Y-48259D01*
X1670Y-49717D01*
X3416Y-50300D01*
X4726Y-50008D01*
X6255Y-48842D01*
X7128Y-47676D01*
G01X17423Y-42425D02*
X24410D01*
X23755Y-40383D01*
X22663Y-39217D01*
X21135Y-38634D01*
X19606Y-38925D01*
X18296Y-39800D01*
X17423Y-41842D01*
X16986Y-43592D01*
Y-45342D01*
X17423Y-47092D01*
X18515Y-48842D01*
X19825Y-50008D01*
X21353Y-50300D01*
X22881Y-49717D01*
X24410Y-47967D01*
G01X35141Y-50300D02*
Y-38634D01*
G01Y-40967D02*
X36233Y-39800D01*
X37325Y-38925D01*
X38853Y-38634D01*
X39944Y-38925D01*
X41255Y-39800D01*
G01X51768Y-50300D02*
Y-32800D01*
G01Y-41550D02*
X52860Y-39800D01*
X54170Y-38925D01*
X55480Y-38634D01*
X57444Y-39217D01*
X58755Y-40383D01*
X59628Y-42425D01*
Y-44758D01*
X59191Y-47092D01*
X58318Y-48842D01*
X56790Y-50008D01*
X55480Y-50300D01*
X54170Y-50008D01*
X52860Y-49134D01*
X51768Y-47676D01*
G01X69923Y-42425D02*
X76910D01*
X76255Y-40383D01*
X75163Y-39217D01*
X73635Y-38634D01*
X72106Y-38925D01*
X70796Y-39800D01*
X69923Y-41842D01*
X69486Y-43592D01*
Y-45342D01*
X69923Y-47092D01*
X71015Y-48842D01*
X72325Y-50008D01*
X73853Y-50300D01*
X75381Y-49717D01*
X76910Y-47967D01*
G01X87641Y-50300D02*
Y-38634D01*
G01Y-40967D02*
X88733Y-39800D01*
X89825Y-38925D01*
X91353Y-38634D01*
X92444Y-38925D01*
X93755Y-39800D01*
G01X125698Y-38634D02*
Y-50300D01*
G01Y-33967D02*
X125261Y-33675D01*
Y-33092D01*
X125698Y-32800D01*
X126135Y-33092D01*
Y-33675D01*
X125698Y-33967D01*
G01X139923Y-48259D02*
X141015Y-49425D01*
X142543Y-50300D01*
X143853D01*
X145163Y-49717D01*
X146036Y-48842D01*
X146473Y-47676D01*
X146255Y-45925D01*
X145381Y-45050D01*
X141451Y-43300D01*
X140578Y-41258D01*
X141015Y-39800D01*
X141888Y-38925D01*
X143198Y-38634D01*
X144508Y-38925D01*
X145818Y-39800D01*
G01X174704Y-54675D02*
X176233Y-55842D01*
X177543Y-56133D01*
X179290Y-55550D01*
X180600Y-54092D01*
X181255Y-51466D01*
Y-38634D01*
G01Y-33967D02*
X180818Y-33675D01*
Y-33092D01*
X181255Y-32800D01*
X181691Y-33092D01*
Y-33675D01*
X181255Y-33967D01*
G01X191986Y-38634D02*
Y-46800D01*
X192860Y-48842D01*
X194170Y-50008D01*
X195698Y-50300D01*
X197226Y-50008D01*
X198536Y-48842D01*
X199410Y-46800D01*
G01Y-50300D02*
Y-38634D01*
G01X209923Y-48259D02*
X211015Y-49425D01*
X212543Y-50300D01*
X213853D01*
X215163Y-49717D01*
X216036Y-48842D01*
X216473Y-47676D01*
X216255Y-45925D01*
X215381Y-45050D01*
X211451Y-43300D01*
X210578Y-41258D01*
X211015Y-39800D01*
X211888Y-38925D01*
X213198Y-38634D01*
X214508Y-38925D01*
X215818Y-39800D01*
G01X230698Y-32800D02*
Y-50300D01*
G01X227641Y-38634D02*
X233755D01*
G01X264388Y-50300D02*
Y-35425D01*
X264825Y-33967D01*
X265698Y-33092D01*
X267008Y-32800D01*
X268318Y-33383D01*
X268973Y-34842D01*
G01X266353Y-39800D02*
X261986D01*
G01X283198Y-50300D02*
X281888Y-50008D01*
X280578Y-48842D01*
X279704Y-46800D01*
X279268Y-44467D01*
X279704Y-42133D01*
X280578Y-40092D01*
X281888Y-38925D01*
X283198Y-38634D01*
X284508Y-38925D01*
X285818Y-40092D01*
X286691Y-42133D01*
X286910Y-44467D01*
X286691Y-46800D01*
X285818Y-48842D01*
X284508Y-50008D01*
X283198Y-50300D01*
G01X297641D02*
Y-38634D01*
G01Y-40967D02*
X298733Y-39800D01*
X299825Y-38925D01*
X301353Y-38634D01*
X302444Y-38925D01*
X303755Y-39800D01*
G01X331113Y-55550D02*
X332423Y-56133D01*
X334170Y-55550D01*
X335261Y-54384D01*
X336135Y-52925D01*
X337444Y-48259D01*
X340283Y-38634D01*
G01X333296D02*
X337444Y-48259D01*
G01X353198Y-50300D02*
X351888Y-50008D01*
X350578Y-48842D01*
X349704Y-46800D01*
X349268Y-44467D01*
X349704Y-42133D01*
X350578Y-40092D01*
X351888Y-38925D01*
X353198Y-38634D01*
X354508Y-38925D01*
X355818Y-40092D01*
X356691Y-42133D01*
X356910Y-44467D01*
X356691Y-46800D01*
X355818Y-48842D01*
X354508Y-50008D01*
X353198Y-50300D01*
G01X366986Y-38634D02*
Y-46800D01*
X367860Y-48842D01*
X369170Y-50008D01*
X370698Y-50300D01*
X372226Y-50008D01*
X373536Y-48842D01*
X374410Y-46800D01*
G01Y-50300D02*
Y-38634D01*
G01X385141Y-50300D02*
Y-38634D01*
G01Y-40967D02*
X386233Y-39800D01*
X387325Y-38925D01*
X388853Y-38634D01*
X389944Y-38925D01*
X391255Y-39800D01*
G01X420141Y-50300D02*
Y-38634D01*
G01Y-40967D02*
X421233Y-39800D01*
X422325Y-38925D01*
X423853Y-38634D01*
X424944Y-38925D01*
X426255Y-39800D01*
G01X437423Y-42425D02*
X444410D01*
X443755Y-40383D01*
X442663Y-39217D01*
X441135Y-38634D01*
X439606Y-38925D01*
X438296Y-39800D01*
X437423Y-41842D01*
X436986Y-43592D01*
Y-45342D01*
X437423Y-47092D01*
X438515Y-48842D01*
X439825Y-50008D01*
X441353Y-50300D01*
X442881Y-49717D01*
X444410Y-47967D01*
G01X456888Y-50300D02*
Y-35425D01*
X457325Y-33967D01*
X458198Y-33092D01*
X459508Y-32800D01*
X460818Y-33383D01*
X461473Y-34842D01*
G01X458853Y-39800D02*
X454486D01*
G01X472423Y-42425D02*
X479410D01*
X478755Y-40383D01*
X477663Y-39217D01*
X476135Y-38634D01*
X474606Y-38925D01*
X473296Y-39800D01*
X472423Y-41842D01*
X471986Y-43592D01*
Y-45342D01*
X472423Y-47092D01*
X473515Y-48842D01*
X474825Y-50008D01*
X476353Y-50300D01*
X477881Y-49717D01*
X479410Y-47967D01*
G01X490141Y-50300D02*
Y-38634D01*
G01Y-40967D02*
X491233Y-39800D01*
X492325Y-38925D01*
X493853Y-38634D01*
X494944Y-38925D01*
X496255Y-39800D01*
G01X507423Y-42425D02*
X514410D01*
X513755Y-40383D01*
X512663Y-39217D01*
X511135Y-38634D01*
X509606Y-38925D01*
X508296Y-39800D01*
X507423Y-41842D01*
X506986Y-43592D01*
Y-45342D01*
X507423Y-47092D01*
X508515Y-48842D01*
X509825Y-50008D01*
X511353Y-50300D01*
X512881Y-49717D01*
X514410Y-47967D01*
G01X524486Y-50300D02*
Y-38634D01*
G01Y-41550D02*
X525360Y-40092D01*
X526670Y-38925D01*
X528416Y-38634D01*
X529944Y-38925D01*
X531255Y-40092D01*
X531910Y-42133D01*
Y-50300D01*
G01X549191Y-40092D02*
X547663Y-38925D01*
X546353Y-38634D01*
X544606Y-39217D01*
X543296Y-40383D01*
X542423Y-42425D01*
X542204Y-44467D01*
X542423Y-46509D01*
X543296Y-48259D01*
X544606Y-49717D01*
X546353Y-50300D01*
X547881Y-49717D01*
X549191Y-48550D01*
G01X559923Y-42425D02*
X566910D01*
X566255Y-40383D01*
X565163Y-39217D01*
X563635Y-38634D01*
X562106Y-38925D01*
X560796Y-39800D01*
X559923Y-41842D01*
X559486Y-43592D01*
Y-45342D01*
X559923Y-47092D01*
X561015Y-48842D01*
X562325Y-50008D01*
X563853Y-50300D01*
X565381Y-49717D01*
X566910Y-47967D01*
G01X598198Y-32800D02*
Y-50300D01*
G01X595141Y-38634D02*
X601255D01*
G01X615698Y-50300D02*
X614388Y-50008D01*
X613078Y-48842D01*
X612204Y-46800D01*
X611768Y-44467D01*
X612204Y-42133D01*
X613078Y-40092D01*
X614388Y-38925D01*
X615698Y-38634D01*
X617008Y-38925D01*
X618318Y-40092D01*
X619191Y-42133D01*
X619410Y-44467D01*
X619191Y-46800D01*
X618318Y-48842D01*
X617008Y-50008D01*
X615698Y-50300D01*
G01X649388D02*
Y-35425D01*
X649825Y-33967D01*
X650698Y-33092D01*
X652008Y-32800D01*
X653318Y-33383D01*
X653973Y-34842D01*
G01X651353Y-39800D02*
X646986D01*
G01X668198Y-38634D02*
Y-50300D01*
G01Y-33967D02*
X667761Y-33675D01*
Y-33092D01*
X668198Y-32800D01*
X668635Y-33092D01*
Y-33675D01*
X668198Y-33967D01*
G01X681986Y-50300D02*
Y-38634D01*
G01Y-41550D02*
X682860Y-40092D01*
X684170Y-38925D01*
X685916Y-38634D01*
X687444Y-38925D01*
X688755Y-40092D01*
X689410Y-42133D01*
Y-50300D01*
G01X707128Y-32800D02*
Y-50300D01*
G01Y-47676D02*
X706255Y-49134D01*
X704944Y-50008D01*
X703416Y-50300D01*
X701670Y-49717D01*
X700360Y-48259D01*
X699486Y-46509D01*
X699268Y-44467D01*
X699486Y-42425D01*
X700360Y-40675D01*
X701670Y-39217D01*
X703416Y-38634D01*
X704944Y-38925D01*
X706036Y-39509D01*
X707128Y-40675D01*
G01X738198Y-32800D02*
Y-50300D01*
G01X735141Y-38634D02*
X741255D01*
G01X751986Y-50300D02*
Y-32800D01*
G01Y-41258D02*
X753078Y-39800D01*
X754170Y-38925D01*
X755916Y-38634D01*
X757226Y-38925D01*
X758755Y-40092D01*
X759410Y-41842D01*
Y-50300D01*
G01X769923Y-42425D02*
X776910D01*
X776255Y-40383D01*
X775163Y-39217D01*
X773635Y-38634D01*
X772106Y-38925D01*
X770796Y-39800D01*
X769923Y-41842D01*
X769486Y-43592D01*
Y-45342D01*
X769923Y-47092D01*
X771015Y-48842D01*
X772325Y-50008D01*
X773853Y-50300D01*
X775381Y-49717D01*
X776910Y-47967D01*
G01X803613D02*
X805360Y-49425D01*
X807325Y-50300D01*
X809071D01*
X810818Y-49425D01*
X812128Y-47967D01*
X812783Y-45925D01*
X812346Y-43884D01*
X811255Y-42133D01*
X809290Y-40967D01*
X806670Y-40383D01*
X805141Y-39217D01*
X804486Y-37175D01*
X804923Y-35133D01*
X806015Y-33675D01*
X807543Y-32800D01*
X809071D01*
X810600Y-33383D01*
X811910Y-34842D01*
G01X830065Y-50300D02*
X821331D01*
Y-32800D01*
X830065D01*
G01X826571Y-41258D02*
X821331D01*
G01X860698Y-38634D02*
Y-50300D01*
G01Y-33967D02*
X860261Y-33675D01*
Y-33092D01*
X860698Y-32800D01*
X861135Y-33092D01*
Y-33675D01*
X860698Y-33967D01*
G01X871648Y-50300D02*
Y-38634D01*
G01Y-41842D02*
X872303Y-40383D01*
X873395Y-39217D01*
X874923Y-38634D01*
X876451Y-39217D01*
X877543Y-40383D01*
X878198Y-41842D01*
Y-50300D01*
G01Y-41842D02*
X878853Y-40383D01*
X879944Y-39217D01*
X881473Y-38634D01*
X883001Y-39217D01*
X884093Y-40383D01*
X884748Y-42133D01*
Y-50300D01*
G01X891768Y-56133D02*
Y-38634D01*
G01Y-41258D02*
X892860Y-39800D01*
X893951Y-38925D01*
X895698Y-38634D01*
X897226Y-38925D01*
X898755Y-40383D01*
X899410Y-42425D01*
X899628Y-44467D01*
X899410Y-46509D01*
X898755Y-48550D01*
X897444Y-49717D01*
X895698Y-50300D01*
X894170Y-50008D01*
X892641Y-49134D01*
X891768Y-47967D01*
G01X909923Y-42425D02*
X916910D01*
X916255Y-40383D01*
X915163Y-39217D01*
X913635Y-38634D01*
X912106Y-38925D01*
X910796Y-39800D01*
X909923Y-41842D01*
X909486Y-43592D01*
Y-45342D01*
X909923Y-47092D01*
X911015Y-48842D01*
X912325Y-50008D01*
X913853Y-50300D01*
X915381Y-49717D01*
X916910Y-47967D01*
G01X934628Y-32800D02*
Y-50300D01*
G01Y-47676D02*
X933755Y-49134D01*
X932444Y-50008D01*
X930916Y-50300D01*
X929170Y-49717D01*
X927860Y-48259D01*
X926986Y-46509D01*
X926768Y-44467D01*
X926986Y-42425D01*
X927860Y-40675D01*
X929170Y-39217D01*
X930916Y-38634D01*
X932444Y-38925D01*
X933536Y-39509D01*
X934628Y-40675D01*
G01X952128Y-50300D02*
Y-38634D01*
G01Y-40675D02*
X951255Y-39509D01*
X949944Y-38925D01*
X948416Y-38634D01*
X946888Y-39217D01*
X945578Y-40383D01*
X944704Y-42133D01*
X944268Y-44467D01*
X944704Y-46800D01*
X945578Y-48550D01*
X946888Y-49717D01*
X948416Y-50300D01*
X949944Y-50008D01*
X951255Y-49134D01*
X952128Y-47967D01*
G01X961986Y-50300D02*
Y-38634D01*
G01Y-41550D02*
X962860Y-40092D01*
X964170Y-38925D01*
X965916Y-38634D01*
X967444Y-38925D01*
X968755Y-40092D01*
X969410Y-42133D01*
Y-50300D01*
G01X986691Y-40092D02*
X985163Y-38925D01*
X983853Y-38634D01*
X982106Y-39217D01*
X980796Y-40383D01*
X979923Y-42425D01*
X979704Y-44467D01*
X979923Y-46509D01*
X980796Y-48259D01*
X982106Y-49717D01*
X983853Y-50300D01*
X985381Y-49717D01*
X986691Y-48550D01*
G01X997423Y-42425D02*
X1004410D01*
X1003755Y-40383D01*
X1002663Y-39217D01*
X1001135Y-38634D01*
X999606Y-38925D01*
X998296Y-39800D01*
X997423Y-41842D01*
X996986Y-43592D01*
Y-45342D01*
X997423Y-47092D01*
X998515Y-48842D01*
X999825Y-50008D01*
X1001353Y-50300D01*
X1002881Y-49717D01*
X1004410Y-47967D01*
G01X1035698Y-32800D02*
Y-50300D01*
G01X1032641Y-38634D02*
X1038755D01*
G01X1050141Y-50300D02*
Y-38634D01*
G01Y-40967D02*
X1051233Y-39800D01*
X1052325Y-38925D01*
X1053853Y-38634D01*
X1054944Y-38925D01*
X1056255Y-39800D01*
G01X1074628Y-50300D02*
Y-38634D01*
G01Y-40675D02*
X1073755Y-39509D01*
X1072444Y-38925D01*
X1070916Y-38634D01*
X1069388Y-39217D01*
X1068078Y-40383D01*
X1067204Y-42133D01*
X1066768Y-44467D01*
X1067204Y-46800D01*
X1068078Y-48550D01*
X1069388Y-49717D01*
X1070916Y-50300D01*
X1072444Y-50008D01*
X1073755Y-49134D01*
X1074628Y-47967D01*
G01X1091691Y-40092D02*
X1090163Y-38925D01*
X1088853Y-38634D01*
X1087106Y-39217D01*
X1085796Y-40383D01*
X1084923Y-42425D01*
X1084704Y-44467D01*
X1084923Y-46509D01*
X1085796Y-48259D01*
X1087106Y-49717D01*
X1088853Y-50300D01*
X1090381Y-49717D01*
X1091691Y-48550D01*
G01X1102423Y-42425D02*
X1109410D01*
X1108755Y-40383D01*
X1107663Y-39217D01*
X1106135Y-38634D01*
X1104606Y-38925D01*
X1103296Y-39800D01*
X1102423Y-41842D01*
X1101986Y-43592D01*
Y-45342D01*
X1102423Y-47092D01*
X1103515Y-48842D01*
X1104825Y-50008D01*
X1106353Y-50300D01*
X1107881Y-49717D01*
X1109410Y-47967D01*
G01X1119923Y-48259D02*
X1121015Y-49425D01*
X1122543Y-50300D01*
X1123853D01*
X1125163Y-49717D01*
X1126036Y-48842D01*
X1126473Y-47676D01*
X1126255Y-45925D01*
X1125381Y-45050D01*
X1121451Y-43300D01*
X1120578Y-41258D01*
X1121015Y-39800D01*
X1121888Y-38925D01*
X1123198Y-38634D01*
X1124508Y-38925D01*
X1125818Y-39800D01*
G01X1158198Y-38634D02*
Y-50300D01*
G01Y-33967D02*
X1157761Y-33675D01*
Y-33092D01*
X1158198Y-32800D01*
X1158635Y-33092D01*
Y-33675D01*
X1158198Y-33967D01*
G01X1171986Y-50300D02*
Y-38634D01*
G01Y-41550D02*
X1172860Y-40092D01*
X1174170Y-38925D01*
X1175916Y-38634D01*
X1177444Y-38925D01*
X1178755Y-40092D01*
X1179410Y-42133D01*
Y-50300D01*
G01X1210698D02*
Y-32800D01*
G01X1232128Y-50300D02*
Y-38634D01*
G01Y-40675D02*
X1231255Y-39509D01*
X1229944Y-38925D01*
X1228416Y-38634D01*
X1226888Y-39217D01*
X1225578Y-40383D01*
X1224704Y-42133D01*
X1224268Y-44467D01*
X1224704Y-46800D01*
X1225578Y-48550D01*
X1226888Y-49717D01*
X1228416Y-50300D01*
X1229944Y-50008D01*
X1231255Y-49134D01*
X1232128Y-47967D01*
G01X1241113Y-55550D02*
X1242423Y-56133D01*
X1244170Y-55550D01*
X1245261Y-54384D01*
X1246135Y-52925D01*
X1247444Y-48259D01*
X1250283Y-38634D01*
G01X1243296D02*
X1247444Y-48259D01*
G01X1259923Y-42425D02*
X1266910D01*
X1266255Y-40383D01*
X1265163Y-39217D01*
X1263635Y-38634D01*
X1262106Y-38925D01*
X1260796Y-39800D01*
X1259923Y-41842D01*
X1259486Y-43592D01*
Y-45342D01*
X1259923Y-47092D01*
X1261015Y-48842D01*
X1262325Y-50008D01*
X1263853Y-50300D01*
X1265381Y-49717D01*
X1266910Y-47967D01*
G01X1277641Y-50300D02*
Y-38634D01*
G01Y-40967D02*
X1278733Y-39800D01*
X1279825Y-38925D01*
X1281353Y-38634D01*
X1282444Y-38925D01*
X1283755Y-39800D01*
G01X1311331Y-32800D02*
Y-50300D01*
X1320065D01*
G01X1329050Y-43009D02*
X1330578Y-40967D01*
X1331888Y-39800D01*
X1333635Y-39217D01*
X1335163Y-39800D01*
X1336255Y-40967D01*
X1337128Y-42717D01*
X1337346Y-44758D01*
X1337128Y-46509D01*
X1336255Y-48259D01*
X1334944Y-49717D01*
X1333416Y-50300D01*
X1331670Y-49717D01*
X1330141Y-47967D01*
X1329268Y-45342D01*
X1329050Y-42425D01*
X1329486Y-38634D01*
X1330141Y-36591D01*
X1331233Y-34550D01*
X1332761Y-33092D01*
X1334290Y-32800D01*
X1335818Y-33383D01*
X1336910Y-34842D01*
G01X1350698Y-50883D02*
X1350261Y-50592D01*
Y-50008D01*
X1350698Y-49717D01*
X1351135Y-50008D01*
Y-50592D01*
X1350698Y-50883D01*
G01X1201883Y1950376D02*
X1207123D01*
G01X1204503D02*
Y1932876D01*
G01X1201883D02*
X1207123D01*
G01X1216326D02*
Y1950376D01*
X1222003Y1935793D01*
X1227680Y1950376D01*
Y1932876D01*
G01X1235136D02*
Y1950376D01*
X1240376D01*
X1242123Y1949501D01*
X1243433Y1947459D01*
X1243870Y1945126D01*
X1243433Y1942793D01*
X1242341Y1941043D01*
X1240376Y1940167D01*
X1235136D01*
G01X1255911Y1927043D02*
X1253728Y1929959D01*
X1252636Y1932876D01*
Y1944542D01*
X1253728Y1947459D01*
X1255911Y1950376D01*
G01X1274503Y1932876D02*
X1272756Y1933168D01*
X1271228Y1934334D01*
X1269918Y1936084D01*
X1269044Y1938126D01*
X1268608Y1940459D01*
Y1942793D01*
X1269044Y1945126D01*
X1269918Y1947168D01*
X1271228Y1948917D01*
X1272756Y1950084D01*
X1274503Y1950376D01*
X1276249Y1950084D01*
X1277778Y1948917D01*
X1279088Y1947168D01*
X1279962Y1945126D01*
X1280398Y1942793D01*
Y1940459D01*
X1279962Y1938126D01*
X1279088Y1936084D01*
X1277778Y1934334D01*
X1276249Y1933168D01*
X1274503Y1932876D01*
G01X1288291D02*
Y1950376D01*
G01Y1941918D02*
X1289383Y1943376D01*
X1290475Y1944251D01*
X1292221Y1944542D01*
X1293531Y1944251D01*
X1295060Y1943084D01*
X1295715Y1941334D01*
Y1932876D01*
G01X1302953D02*
Y1944542D01*
G01Y1941334D02*
X1303608Y1942793D01*
X1304700Y1943959D01*
X1306228Y1944542D01*
X1307756Y1943959D01*
X1308848Y1942793D01*
X1309503Y1941334D01*
Y1932876D01*
G01Y1941334D02*
X1310158Y1942793D01*
X1311249Y1943959D01*
X1312778Y1944542D01*
X1314306Y1943959D01*
X1315398Y1942793D01*
X1316053Y1941043D01*
Y1932876D01*
G01X1328095Y1927043D02*
X1330278Y1929959D01*
X1331370Y1932876D01*
Y1944542D01*
X1330278Y1947459D01*
X1328095Y1950376D01*
G01X1180218Y1969859D02*
X1181965Y1968401D01*
X1183930Y1967526D01*
X1185676D01*
X1187423Y1968401D01*
X1188733Y1969859D01*
X1189388Y1971901D01*
X1188951Y1973942D01*
X1187860Y1975693D01*
X1185895Y1976859D01*
X1183275Y1977443D01*
X1181746Y1978609D01*
X1181091Y1980651D01*
X1181528Y1982693D01*
X1182620Y1984151D01*
X1184148Y1985026D01*
X1185676D01*
X1187205Y1984443D01*
X1188515Y1982984D01*
G01X1206670Y1967526D02*
X1197936D01*
Y1985026D01*
X1206670D01*
G01X1203176Y1976568D02*
X1197936D01*
G01X1234683Y1985026D02*
X1239923D01*
G01X1237303D02*
Y1967526D01*
G01X1234683D02*
X1239923D01*
G01X1249126D02*
Y1985026D01*
X1254803Y1970443D01*
X1260480Y1985026D01*
Y1967526D01*
G01X1267936D02*
Y1985026D01*
X1273176D01*
X1274923Y1984151D01*
X1276233Y1982109D01*
X1276670Y1979776D01*
X1276233Y1977443D01*
X1275141Y1975693D01*
X1273176Y1974817D01*
X1267936D01*
G01X1294170Y1967526D02*
X1285436D01*
Y1985026D01*
X1294170D01*
G01X1290676Y1976568D02*
X1285436D01*
G01X1302500Y1967526D02*
Y1985026D01*
X1306866D01*
X1308613Y1984151D01*
X1309923Y1982984D01*
X1311015Y1981235D01*
X1311888Y1979192D01*
X1312106Y1976276D01*
X1311888Y1973359D01*
X1311015Y1971317D01*
X1309923Y1969567D01*
X1308613Y1968401D01*
X1306866Y1967526D01*
X1302500D01*
G01X1319344D02*
X1324803Y1985026D01*
X1330262Y1967526D01*
G01X1328296Y1973651D02*
X1321309D01*
G01X1337281Y1967526D02*
Y1985026D01*
X1347325Y1967526D01*
Y1985026D01*
G01X1364606Y1983567D02*
X1363296Y1984443D01*
X1361768Y1985026D01*
X1360021D01*
X1358056Y1984151D01*
X1356528Y1982693D01*
X1355436Y1980942D01*
X1354563Y1978026D01*
X1354344Y1975401D01*
X1354781Y1972776D01*
X1355436Y1971026D01*
X1356746Y1969276D01*
X1358275Y1968109D01*
X1359803Y1967526D01*
X1361331D01*
X1362860Y1968109D01*
X1364170Y1968984D01*
X1365262Y1970150D01*
G01X1381670Y1967526D02*
X1372936D01*
Y1985026D01*
X1381670D01*
G01X1378176Y1976568D02*
X1372936D01*
G01X1412303Y1985026D02*
Y1967526D01*
G01X1407281Y1985026D02*
X1417325D01*
G01X1424344Y1967526D02*
X1429803Y1985026D01*
X1435262Y1967526D01*
G01X1433296Y1973651D02*
X1426309D01*
G01X1449049Y1976859D02*
X1449923Y1977734D01*
X1450578Y1979192D01*
X1451015Y1981235D01*
X1450578Y1982984D01*
X1449705Y1984151D01*
X1448176Y1985026D01*
X1442281D01*
Y1967526D01*
X1449486D01*
X1451015Y1968692D01*
X1451888Y1970443D01*
X1452325Y1972484D01*
X1451888Y1974526D01*
X1450578Y1976276D01*
X1449049Y1976859D01*
X1442281D01*
G01X1460436Y1985026D02*
Y1967526D01*
X1469170D01*
G01X1486670D02*
X1477936D01*
Y1985026D01*
X1486670D01*
G01X1483176Y1976568D02*
X1477936D01*
G01X1499803Y1966943D02*
X1499366Y1967234D01*
Y1967818D01*
X1499803Y1968109D01*
X1500240Y1967818D01*
Y1967234D01*
X1499803Y1966943D01*
G01Y1974817D02*
X1499366Y1975109D01*
Y1975693D01*
X1499803Y1975984D01*
X1500240Y1975693D01*
Y1975109D01*
X1499803Y1974817D01*
G01X1530436Y1985026D02*
Y1967526D01*
X1539170D01*
G01X1548155Y1974817D02*
X1549683Y1976859D01*
X1550993Y1978026D01*
X1552740Y1978609D01*
X1554268Y1978026D01*
X1555360Y1976859D01*
X1556233Y1975109D01*
X1556451Y1973068D01*
X1556233Y1971317D01*
X1555360Y1969567D01*
X1554049Y1968109D01*
X1552521Y1967526D01*
X1550775Y1968109D01*
X1549246Y1969859D01*
X1548373Y1972484D01*
X1548155Y1975401D01*
X1548591Y1979192D01*
X1549246Y1981235D01*
X1550338Y1983276D01*
X1551866Y1984734D01*
X1553395Y1985026D01*
X1554923Y1984443D01*
X1556015Y1982984D01*
G01X1234700Y1900850D02*
X1236009Y1899392D01*
X1237538Y1898518D01*
X1239503Y1898226D01*
X1241468Y1898809D01*
X1242996Y1899976D01*
X1244088Y1902017D01*
X1244306Y1904351D01*
X1243870Y1906684D01*
X1242778Y1908143D01*
X1241249Y1909309D01*
X1239721Y1909601D01*
X1238193Y1909309D01*
X1236228Y1908143D01*
X1236883Y1915726D01*
X1242778D01*
G01X1257003D02*
X1255256Y1915143D01*
X1253946Y1913684D01*
X1253073Y1911935D01*
X1252418Y1909601D01*
X1252200Y1906976D01*
X1252418Y1904351D01*
X1253073Y1902017D01*
X1253946Y1900267D01*
X1255256Y1898809D01*
X1257003Y1898226D01*
X1258749Y1898809D01*
X1260060Y1900267D01*
X1260933Y1902017D01*
X1261588Y1904351D01*
X1261806Y1906976D01*
X1261588Y1909601D01*
X1260933Y1911935D01*
X1260060Y1913684D01*
X1258749Y1915143D01*
X1257003Y1915726D01*
G01X1274503Y1897643D02*
X1274066Y1897934D01*
Y1898518D01*
X1274503Y1898809D01*
X1274940Y1898518D01*
Y1897934D01*
X1274503Y1897643D01*
G01X1292003Y1915726D02*
X1290256Y1915143D01*
X1288946Y1913684D01*
X1288073Y1911935D01*
X1287418Y1909601D01*
X1287200Y1906976D01*
X1287418Y1904351D01*
X1288073Y1902017D01*
X1288946Y1900267D01*
X1290256Y1898809D01*
X1292003Y1898226D01*
X1293749Y1898809D01*
X1295060Y1900267D01*
X1295933Y1902017D01*
X1296588Y1904351D01*
X1296806Y1906976D01*
X1296588Y1909601D01*
X1295933Y1911935D01*
X1295060Y1913684D01*
X1293749Y1915143D01*
X1292003Y1915726D01*
G01X1372953Y1950376D02*
X1376009Y1932876D01*
X1379503Y1950376D01*
X1382996Y1932876D01*
X1386053Y1950376D01*
G01X1394383D02*
X1399623D01*
G01X1397003D02*
Y1932876D01*
G01X1394383D02*
X1399623D01*
G01X1409700D02*
Y1950376D01*
X1414066D01*
X1415813Y1949501D01*
X1417123Y1948334D01*
X1418215Y1946585D01*
X1419088Y1944542D01*
X1419306Y1941626D01*
X1419088Y1938709D01*
X1418215Y1936667D01*
X1417123Y1934917D01*
X1415813Y1933751D01*
X1414066Y1932876D01*
X1409700D01*
G01X1432003Y1950376D02*
Y1932876D01*
G01X1426981Y1950376D02*
X1437025D01*
G01X1444918Y1932876D02*
Y1950376D01*
G01X1454088D02*
Y1932876D01*
G01Y1941626D02*
X1444918D01*
G01X1465911Y1927043D02*
X1463728Y1929959D01*
X1462636Y1932876D01*
Y1944542D01*
X1463728Y1947459D01*
X1465911Y1950376D01*
G01X1477953Y1932876D02*
Y1944542D01*
G01Y1941334D02*
X1478608Y1942793D01*
X1479700Y1943959D01*
X1481228Y1944542D01*
X1482756Y1943959D01*
X1483848Y1942793D01*
X1484503Y1941334D01*
Y1932876D01*
G01Y1941334D02*
X1485158Y1942793D01*
X1486249Y1943959D01*
X1487778Y1944542D01*
X1489306Y1943959D01*
X1490398Y1942793D01*
X1491053Y1941043D01*
Y1932876D01*
G01X1502003Y1944542D02*
Y1932876D01*
G01Y1949209D02*
X1501566Y1949501D01*
Y1950084D01*
X1502003Y1950376D01*
X1502440Y1950084D01*
Y1949501D01*
X1502003Y1949209D01*
G01X1519503Y1932876D02*
Y1950376D01*
G01X1533728Y1934917D02*
X1534820Y1933751D01*
X1536348Y1932876D01*
X1537658D01*
X1538968Y1933459D01*
X1539841Y1934334D01*
X1540278Y1935500D01*
X1540060Y1937251D01*
X1539186Y1938126D01*
X1535256Y1939876D01*
X1534383Y1941918D01*
X1534820Y1943376D01*
X1535693Y1944251D01*
X1537003Y1944542D01*
X1538313Y1944251D01*
X1539623Y1943376D01*
G01X1555595Y1927043D02*
X1557778Y1929959D01*
X1558870Y1932876D01*
Y1944542D01*
X1557778Y1947459D01*
X1555595Y1950376D01*
G01X1445355Y1905517D02*
X1446883Y1907559D01*
X1448193Y1908726D01*
X1449940Y1909309D01*
X1451468Y1908726D01*
X1452560Y1907559D01*
X1453433Y1905809D01*
X1453651Y1903768D01*
X1453433Y1902017D01*
X1452560Y1900267D01*
X1451249Y1898809D01*
X1449721Y1898226D01*
X1447975Y1898809D01*
X1446446Y1900559D01*
X1445573Y1903184D01*
X1445355Y1906101D01*
X1445791Y1909892D01*
X1446446Y1911935D01*
X1447538Y1913976D01*
X1449066Y1915434D01*
X1450595Y1915726D01*
X1452123Y1915143D01*
X1453215Y1913684D01*
G01X1467003Y1897643D02*
X1466566Y1897934D01*
Y1898518D01*
X1467003Y1898809D01*
X1467440Y1898518D01*
Y1897934D01*
X1467003Y1897643D01*
G01X1484503Y1915726D02*
X1482756Y1915143D01*
X1481446Y1913684D01*
X1480573Y1911935D01*
X1479918Y1909601D01*
X1479700Y1906976D01*
X1479918Y1904351D01*
X1480573Y1902017D01*
X1481446Y1900267D01*
X1482756Y1898809D01*
X1484503Y1898226D01*
X1486249Y1898809D01*
X1487560Y1900267D01*
X1488433Y1902017D01*
X1489088Y1904351D01*
X1489306Y1906976D01*
X1489088Y1909601D01*
X1488433Y1911935D01*
X1487560Y1913684D01*
X1486249Y1915143D01*
X1484503Y1915726D01*
G01X1607003Y1950376D02*
Y1932876D01*
G01X1601981Y1950376D02*
X1612025D01*
G01X1624503Y1932876D02*
Y1940751D01*
X1620136Y1950376D01*
G01X1628870D02*
X1624503Y1940751D01*
G01X1637636Y1932876D02*
Y1950376D01*
X1642876D01*
X1644623Y1949501D01*
X1645933Y1947459D01*
X1646370Y1945126D01*
X1645933Y1942793D01*
X1644841Y1941043D01*
X1642876Y1940167D01*
X1637636D01*
G01X1663870Y1932876D02*
X1655136D01*
Y1950376D01*
X1663870D01*
G01X1660376Y1941918D02*
X1655136D01*
G01X1619918Y1900559D02*
X1621665Y1899101D01*
X1623630Y1898226D01*
X1625376D01*
X1627123Y1899101D01*
X1628433Y1900559D01*
X1629088Y1902601D01*
X1628651Y1904642D01*
X1627560Y1906393D01*
X1625595Y1907559D01*
X1622975Y1908143D01*
X1621446Y1909309D01*
X1620791Y1911351D01*
X1621228Y1913393D01*
X1622320Y1914851D01*
X1623848Y1915726D01*
X1625376D01*
X1626905Y1915143D01*
X1628215Y1913684D01*
G01X1646370Y1898226D02*
X1637636D01*
Y1915726D01*
X1646370D01*
G01X1642876Y1907268D02*
X1637636D01*
G01X1707636Y1932876D02*
Y1950376D01*
X1713095D01*
X1714841Y1949501D01*
X1715933Y1948334D01*
X1716370Y1946001D01*
X1715933Y1943667D01*
X1714623Y1942209D01*
X1713095Y1941334D01*
X1707636D01*
G01X1713095D02*
X1716370Y1932876D01*
G01X1726228Y1940751D02*
X1733215D01*
X1732560Y1942793D01*
X1731468Y1943959D01*
X1729940Y1944542D01*
X1728411Y1944251D01*
X1727101Y1943376D01*
X1726228Y1941334D01*
X1725791Y1939584D01*
Y1937834D01*
X1726228Y1936084D01*
X1727320Y1934334D01*
X1728630Y1933168D01*
X1730158Y1932876D01*
X1731686Y1933459D01*
X1733215Y1935209D01*
G01X1745693Y1932876D02*
Y1947751D01*
X1746130Y1949209D01*
X1747003Y1950084D01*
X1748313Y1950376D01*
X1749623Y1949793D01*
X1750278Y1948334D01*
G01X1747658Y1943376D02*
X1743291D01*
G01X1764503Y1932293D02*
X1764066Y1932584D01*
Y1933168D01*
X1764503Y1933459D01*
X1764940Y1933168D01*
Y1932584D01*
X1764503Y1932293D01*
G01X1795136Y1932876D02*
Y1950376D01*
X1800376D01*
X1802123Y1949501D01*
X1803433Y1947459D01*
X1803870Y1945126D01*
X1803433Y1942793D01*
X1802341Y1941043D01*
X1800376Y1940167D01*
X1795136D01*
G01X1817003Y1932876D02*
Y1950376D01*
G01X1838433Y1932876D02*
Y1944542D01*
G01Y1942501D02*
X1837560Y1943667D01*
X1836249Y1944251D01*
X1834721Y1944542D01*
X1833193Y1943959D01*
X1831883Y1942793D01*
X1831009Y1941043D01*
X1830573Y1938709D01*
X1831009Y1936376D01*
X1831883Y1934626D01*
X1833193Y1933459D01*
X1834721Y1932876D01*
X1836249Y1933168D01*
X1837560Y1934042D01*
X1838433Y1935209D01*
G01X1848291Y1932876D02*
Y1944542D01*
G01Y1941626D02*
X1849165Y1943084D01*
X1850475Y1944251D01*
X1852221Y1944542D01*
X1853749Y1944251D01*
X1855060Y1943084D01*
X1855715Y1941043D01*
Y1932876D01*
G01X1866228Y1940751D02*
X1873215D01*
X1872560Y1942793D01*
X1871468Y1943959D01*
X1869940Y1944542D01*
X1868411Y1944251D01*
X1867101Y1943376D01*
X1866228Y1941334D01*
X1865791Y1939584D01*
Y1937834D01*
X1866228Y1936084D01*
X1867320Y1934334D01*
X1868630Y1933168D01*
X1870158Y1932876D01*
X1871686Y1933459D01*
X1873215Y1935209D01*
G01X1751386Y1915726D02*
Y1898226D01*
X1760120D01*
G01X1768450Y1900850D02*
X1769759Y1899392D01*
X1771288Y1898518D01*
X1773253Y1898226D01*
X1775218Y1898809D01*
X1776746Y1899976D01*
X1777838Y1902017D01*
X1778056Y1904351D01*
X1777620Y1906684D01*
X1776528Y1908143D01*
X1774999Y1909309D01*
X1773471Y1909601D01*
X1771943Y1909309D01*
X1769978Y1908143D01*
X1770633Y1915726D01*
X1776528D01*
G01X1786823Y1897643D02*
X1794683Y1915726D01*
G01X1803886D02*
Y1898226D01*
X1812620D01*
G01X1825316D02*
X1825753Y1902017D01*
X1826408Y1905226D01*
X1827281Y1908143D01*
X1828373Y1911351D01*
X1830120Y1915726D01*
X1821386D01*
G01X1912500Y1932293D02*
X1922106Y1945126D01*
G01X1917303Y1947459D02*
Y1929959D01*
G01X1922106Y1932293D02*
X1912500Y1945126D01*
G01X1910753Y1938709D02*
X1923853D01*
G01X1949465D02*
X1955141D01*
G01X1982500Y1932876D02*
Y1950376D01*
X1986866D01*
X1988613Y1949501D01*
X1989923Y1948334D01*
X1991015Y1946585D01*
X1991888Y1944542D01*
X1992106Y1941626D01*
X1991888Y1938709D01*
X1991015Y1936667D01*
X1989923Y1934917D01*
X1988613Y1933751D01*
X1986866Y1932876D01*
X1982500D01*
G01X2001528Y1940751D02*
X2008515D01*
X2007860Y1942793D01*
X2006768Y1943959D01*
X2005240Y1944542D01*
X2003711Y1944251D01*
X2002401Y1943376D01*
X2001528Y1941334D01*
X2001091Y1939584D01*
Y1937834D01*
X2001528Y1936084D01*
X2002620Y1934334D01*
X2003930Y1933168D01*
X2005458Y1932876D01*
X2006986Y1933459D01*
X2008515Y1935209D01*
G01X2018591Y1932876D02*
Y1944542D01*
G01Y1941626D02*
X2019465Y1943084D01*
X2020775Y1944251D01*
X2022521Y1944542D01*
X2024049Y1944251D01*
X2025360Y1943084D01*
X2026015Y1941043D01*
Y1932876D01*
G01X2039803D02*
X2038493Y1933168D01*
X2037183Y1934334D01*
X2036309Y1936376D01*
X2035873Y1938709D01*
X2036309Y1941043D01*
X2037183Y1943084D01*
X2038493Y1944251D01*
X2039803Y1944542D01*
X2041113Y1944251D01*
X2042423Y1943084D01*
X2043296Y1941043D01*
X2043515Y1938709D01*
X2043296Y1936376D01*
X2042423Y1934334D01*
X2041113Y1933168D01*
X2039803Y1932876D01*
G01X2057303Y1950376D02*
Y1932876D01*
G01X2054246Y1944542D02*
X2060360D01*
G01X2071528Y1940751D02*
X2078515D01*
X2077860Y1942793D01*
X2076768Y1943959D01*
X2075240Y1944542D01*
X2073711Y1944251D01*
X2072401Y1943376D01*
X2071528Y1941334D01*
X2071091Y1939584D01*
Y1937834D01*
X2071528Y1936084D01*
X2072620Y1934334D01*
X2073930Y1933168D01*
X2075458Y1932876D01*
X2076986Y1933459D01*
X2078515Y1935209D01*
G01X2089028Y1934917D02*
X2090120Y1933751D01*
X2091648Y1932876D01*
X2092958D01*
X2094268Y1933459D01*
X2095141Y1934334D01*
X2095578Y1935500D01*
X2095360Y1937251D01*
X2094486Y1938126D01*
X2090556Y1939876D01*
X2089683Y1941918D01*
X2090120Y1943376D01*
X2090993Y1944251D01*
X2092303Y1944542D01*
X2093613Y1944251D01*
X2094923Y1943376D01*
G01X2127303Y1950376D02*
Y1932876D01*
G01X2124246Y1944542D02*
X2130360D01*
G01X2141091Y1932876D02*
Y1950376D01*
G01Y1941918D02*
X2142183Y1943376D01*
X2143275Y1944251D01*
X2145021Y1944542D01*
X2146331Y1944251D01*
X2147860Y1943084D01*
X2148515Y1941334D01*
Y1932876D01*
G01X2166233D02*
Y1944542D01*
G01Y1942501D02*
X2165360Y1943667D01*
X2164049Y1944251D01*
X2162521Y1944542D01*
X2160993Y1943959D01*
X2159683Y1942793D01*
X2158809Y1941043D01*
X2158373Y1938709D01*
X2158809Y1936376D01*
X2159683Y1934626D01*
X2160993Y1933459D01*
X2162521Y1932876D01*
X2164049Y1933168D01*
X2165360Y1934042D01*
X2166233Y1935209D01*
G01X2179803Y1950376D02*
Y1932876D01*
G01X2176746Y1944542D02*
X2182860D01*
G01X2214803Y1950376D02*
Y1932876D01*
G01X2211746Y1944542D02*
X2217860D01*
G01X2228591Y1932876D02*
Y1950376D01*
G01Y1941918D02*
X2229683Y1943376D01*
X2230775Y1944251D01*
X2232521Y1944542D01*
X2233831Y1944251D01*
X2235360Y1943084D01*
X2236015Y1941334D01*
Y1932876D01*
G01X2249803Y1944542D02*
Y1932876D01*
G01Y1949209D02*
X2249366Y1949501D01*
Y1950084D01*
X2249803Y1950376D01*
X2250240Y1950084D01*
Y1949501D01*
X2249803Y1949209D01*
G01X2264028Y1934917D02*
X2265120Y1933751D01*
X2266648Y1932876D01*
X2267958D01*
X2269268Y1933459D01*
X2270141Y1934334D01*
X2270578Y1935500D01*
X2270360Y1937251D01*
X2269486Y1938126D01*
X2265556Y1939876D01*
X2264683Y1941918D01*
X2265120Y1943376D01*
X2265993Y1944251D01*
X2267303Y1944542D01*
X2268613Y1944251D01*
X2269923Y1943376D01*
G01X2299683Y1950376D02*
X2304923D01*
G01X2302303D02*
Y1932876D01*
G01X2299683D02*
X2304923D01*
G01X2313253D02*
Y1944542D01*
G01Y1941334D02*
X2313908Y1942793D01*
X2315000Y1943959D01*
X2316528Y1944542D01*
X2318056Y1943959D01*
X2319148Y1942793D01*
X2319803Y1941334D01*
Y1932876D01*
G01Y1941334D02*
X2320458Y1942793D01*
X2321549Y1943959D01*
X2323078Y1944542D01*
X2324606Y1943959D01*
X2325698Y1942793D01*
X2326353Y1941043D01*
Y1932876D01*
G01X2333373Y1927043D02*
Y1944542D01*
G01Y1941918D02*
X2334465Y1943376D01*
X2335556Y1944251D01*
X2337303Y1944542D01*
X2338831Y1944251D01*
X2340360Y1942793D01*
X2341015Y1940751D01*
X2341233Y1938709D01*
X2341015Y1936667D01*
X2340360Y1934626D01*
X2339049Y1933459D01*
X2337303Y1932876D01*
X2335775Y1933168D01*
X2334246Y1934042D01*
X2333373Y1935209D01*
G01X2351528Y1940751D02*
X2358515D01*
X2357860Y1942793D01*
X2356768Y1943959D01*
X2355240Y1944542D01*
X2353711Y1944251D01*
X2352401Y1943376D01*
X2351528Y1941334D01*
X2351091Y1939584D01*
Y1937834D01*
X2351528Y1936084D01*
X2352620Y1934334D01*
X2353930Y1933168D01*
X2355458Y1932876D01*
X2356986Y1933459D01*
X2358515Y1935209D01*
G01X2376233Y1950376D02*
Y1932876D01*
G01Y1935500D02*
X2375360Y1934042D01*
X2374049Y1933168D01*
X2372521Y1932876D01*
X2370775Y1933459D01*
X2369465Y1934917D01*
X2368591Y1936667D01*
X2368373Y1938709D01*
X2368591Y1940751D01*
X2369465Y1942501D01*
X2370775Y1943959D01*
X2372521Y1944542D01*
X2374049Y1944251D01*
X2375141Y1943667D01*
X2376233Y1942501D01*
G01X2393733Y1932876D02*
Y1944542D01*
G01Y1942501D02*
X2392860Y1943667D01*
X2391549Y1944251D01*
X2390021Y1944542D01*
X2388493Y1943959D01*
X2387183Y1942793D01*
X2386309Y1941043D01*
X2385873Y1938709D01*
X2386309Y1936376D01*
X2387183Y1934626D01*
X2388493Y1933459D01*
X2390021Y1932876D01*
X2391549Y1933168D01*
X2392860Y1934042D01*
X2393733Y1935209D01*
G01X2403591Y1932876D02*
Y1944542D01*
G01Y1941626D02*
X2404465Y1943084D01*
X2405775Y1944251D01*
X2407521Y1944542D01*
X2409049Y1944251D01*
X2410360Y1943084D01*
X2411015Y1941043D01*
Y1932876D01*
G01X2428296Y1943084D02*
X2426768Y1944251D01*
X2425458Y1944542D01*
X2423711Y1943959D01*
X2422401Y1942793D01*
X2421528Y1940751D01*
X2421309Y1938709D01*
X2421528Y1936667D01*
X2422401Y1934917D01*
X2423711Y1933459D01*
X2425458Y1932876D01*
X2426986Y1933459D01*
X2428296Y1934626D01*
G01X2439028Y1940751D02*
X2446015D01*
X2445360Y1942793D01*
X2444268Y1943959D01*
X2442740Y1944542D01*
X2441211Y1944251D01*
X2439901Y1943376D01*
X2439028Y1941334D01*
X2438591Y1939584D01*
Y1937834D01*
X2439028Y1936084D01*
X2440120Y1934334D01*
X2441430Y1933168D01*
X2442958Y1932876D01*
X2444486Y1933459D01*
X2446015Y1935209D01*
G01X1987303Y1909892D02*
Y1898226D01*
G01Y1914559D02*
X1986866Y1914851D01*
Y1915434D01*
X1987303Y1915726D01*
X1987740Y1915434D01*
Y1914851D01*
X1987303Y1914559D01*
G01X2001528Y1900267D02*
X2002620Y1899101D01*
X2004148Y1898226D01*
X2005458D01*
X2006768Y1898809D01*
X2007641Y1899684D01*
X2008078Y1900850D01*
X2007860Y1902601D01*
X2006986Y1903476D01*
X2003056Y1905226D01*
X2002183Y1907268D01*
X2002620Y1908726D01*
X2003493Y1909601D01*
X2004803Y1909892D01*
X2006113Y1909601D01*
X2007423Y1908726D01*
G01X2034781Y1898226D02*
Y1915726D01*
X2044825Y1898226D01*
Y1915726D01*
G01X2057303Y1898226D02*
X2055556Y1898518D01*
X2054028Y1899684D01*
X2052718Y1901434D01*
X2051844Y1903476D01*
X2051408Y1905809D01*
Y1908143D01*
X2051844Y1910476D01*
X2052718Y1912518D01*
X2054028Y1914267D01*
X2055556Y1915434D01*
X2057303Y1915726D01*
X2059049Y1915434D01*
X2060578Y1914267D01*
X2061888Y1912518D01*
X2062762Y1910476D01*
X2063198Y1908143D01*
Y1905809D01*
X2062762Y1903476D01*
X2061888Y1901434D01*
X2060578Y1899684D01*
X2059049Y1898518D01*
X2057303Y1898226D01*
G01X2074803Y1915726D02*
Y1898226D01*
G01X2069781Y1915726D02*
X2079825D01*
G01X2106091Y1909892D02*
Y1901726D01*
X2106965Y1899684D01*
X2108275Y1898518D01*
X2109803Y1898226D01*
X2111331Y1898518D01*
X2112641Y1899684D01*
X2113515Y1901726D01*
G01Y1898226D02*
Y1909892D01*
G01X2124028Y1900267D02*
X2125120Y1899101D01*
X2126648Y1898226D01*
X2127958D01*
X2129268Y1898809D01*
X2130141Y1899684D01*
X2130578Y1900850D01*
X2130360Y1902601D01*
X2129486Y1903476D01*
X2125556Y1905226D01*
X2124683Y1907268D01*
X2125120Y1908726D01*
X2125993Y1909601D01*
X2127303Y1909892D01*
X2128613Y1909601D01*
X2129923Y1908726D01*
G01X2141528Y1906101D02*
X2148515D01*
X2147860Y1908143D01*
X2146768Y1909309D01*
X2145240Y1909892D01*
X2143711Y1909601D01*
X2142401Y1908726D01*
X2141528Y1906684D01*
X2141091Y1904934D01*
Y1903184D01*
X2141528Y1901434D01*
X2142620Y1899684D01*
X2143930Y1898518D01*
X2145458Y1898226D01*
X2146986Y1898809D01*
X2148515Y1900559D01*
G01X2166233Y1915726D02*
Y1898226D01*
G01Y1900850D02*
X2165360Y1899392D01*
X2164049Y1898518D01*
X2162521Y1898226D01*
X2160775Y1898809D01*
X2159465Y1900267D01*
X2158591Y1902017D01*
X2158373Y1904059D01*
X2158591Y1906101D01*
X2159465Y1907851D01*
X2160775Y1909309D01*
X2162521Y1909892D01*
X2164049Y1909601D01*
X2165141Y1909017D01*
X2166233Y1907851D01*
G01X-7874Y0D02*
X-75552D01*
G02X-90552Y15000I0J15000D01*
G01Y519024D01*
G02X-75552Y534024I15000J0D01*
G01X-7874D01*
G01Y1030087D02*
X-75552D01*
G03X-90552Y1015087I0J-15000D01*
G01Y1001780D01*
G03X-75552Y986780I15000J0D01*
G01X-7874D01*
G01Y1992126D02*
X-75552D01*
G03X-90552Y1977126I0J-15000D01*
G01Y1915165D01*
G03X-75552Y1900165I15000J0D01*
G01X-7874D01*
G01X1023228Y1618051D02*
Y1675945D01*
G02X1028701Y1681417I5472J0D01*
G01X1033465D01*
X1037402Y1685354D01*
Y1988189D01*
G03X1033465Y1992126I-3937J0D01*
G01X3937D01*
G03X0Y1988189I0J-3937D01*
G01Y1661189D01*
X1969Y1659220D01*
X17323D01*
G02Y1650559I0J-4331D01*
G01X1969D01*
X0Y1648591D01*
Y1243866D01*
X1969Y1241898D01*
X17323D01*
G02Y1233236I0J-4331D01*
G01X1969D01*
X0Y1231268D01*
Y747803D01*
X1969Y745835D01*
X17323D01*
G02Y737173I0J-4331D01*
G01X1969D01*
X0Y735205D01*
Y3937D01*
G03X3937Y0I3937J0D01*
G01X121260D01*
X127310Y11888D01*
G03X127953Y14567I-5263J2680D01*
G01Y17717D01*
G02X139764I5906J0D01*
G01Y14567D01*
G03X140406Y11888I5906J-1D01*
G01X146457Y0D01*
X1033465D01*
G03X1037402Y3937I0J3937D01*
G01Y1424882D01*
X1033465Y1428819D01*
X1028701D01*
G02X1023228Y1434291I0J5473D01*
G01Y1609902D01*
X1021260Y1611870D01*
X993681D01*
G02Y1616083I0J2107D01*
G01X1021260D01*
X1023228Y1618051D01*
G01X-7874Y39059D02*
G03X0I3937J0D01*
G01Y8350D02*
G03X-7874I-3937J0D01*
G01D02*
Y0D01*
G01Y251657D02*
Y39059D01*
G01X0Y251657D02*
G03X-7874I-3937J0D01*
G01Y282366D02*
G03X0I3937J0D01*
G01X-7874Y494965D02*
Y282366D01*
G01Y525673D02*
G03X0I3937J0D01*
G01Y494965D02*
G03X-7874I-3937J0D01*
G01Y534024D02*
Y525673D01*
G01X30000Y991000D02*
Y997000D01*
G01X25000Y988000D02*
X8000Y1005000D01*
G01X0Y993079D02*
G03X-7874I-3937J0D01*
G01Y986780D02*
Y993079D01*
G01X27825Y995000D02*
X10500Y1012325D01*
G01D02*
Y1044000D01*
G01D02*
X24000Y1057500D01*
G01D02*
X41000D01*
G01X30000Y997000D02*
X13000Y1014000D01*
G01D02*
Y1043500D01*
G01D02*
X23500Y1054000D01*
G01D02*
X42000D01*
G01X8000Y1005000D02*
Y1044500D01*
G01D02*
X23291Y1059791D01*
G01D02*
Y1062791D01*
G01X-7874Y1023787D02*
G03X0I3937J0D01*
G01X-7874D02*
Y1030087D01*
G01X30700Y1308600D02*
X32034D01*
G01D02*
X34300Y1306334D01*
G01D02*
X35726D01*
G01D02*
X100260Y1241800D01*
G01X100120Y1236000D02*
X37920Y1298200D01*
G01D02*
X30300D01*
G01D02*
X26500Y1302000D01*
G01D02*
Y1305121D01*
G01X44855Y1311000D02*
X38500D01*
G01X44451Y1308434D02*
X36170D01*
G01X30000Y1305000D02*
X30766Y1304234D01*
G01D02*
X34856D01*
G01D02*
X100590Y1238500D01*
G01X33938Y1311000D02*
X36438Y1313500D01*
G01D02*
X45325D01*
G01X39779Y1465705D02*
X28000Y1453926D01*
G01D02*
Y1444000D01*
G01X-7874Y1930791D02*
Y1900165D01*
G01X0Y1930791D02*
G03X-7874I-3937J0D01*
G01X30200Y1970300D02*
X31225Y1969275D01*
G01D02*
X130025D01*
G01X-7874Y1961500D02*
G03X0I3937J0D01*
G01X-7874Y1992126D02*
Y1961500D01*
G01X64000Y230000D02*
Y69661D01*
G01D02*
X72500Y61161D01*
G01X56024Y291176D02*
X97400Y249800D01*
G01D02*
Y220200D01*
G01X70500Y242988D02*
Y236500D01*
G01D02*
X64000Y230000D01*
G01X56024Y292549D02*
Y291176D01*
G01X143500Y402500D02*
X94000D01*
G01D02*
X90500Y406000D01*
G01D02*
Y438500D01*
G01D02*
X69000Y460000D01*
G01D02*
Y468900D01*
G01D02*
X88400Y488300D01*
G01X90500Y484673D02*
X72500Y466673D01*
G01X88400Y488300D02*
Y597460D01*
G01X90500Y598330D02*
Y484673D01*
G01X71000Y524464D02*
X76900Y530364D01*
G01D02*
Y572700D01*
G01X88400Y597460D02*
X74651Y611209D01*
G01D02*
Y626449D01*
G01D02*
X47600Y653500D01*
G01X70500Y634000D02*
X76751Y627749D01*
G01D02*
Y612079D01*
G01D02*
X90500Y598330D01*
G01X76900Y572700D02*
X64700Y584900D01*
G01D02*
Y633430D01*
G01X88600Y623300D02*
X75000Y636900D01*
G01X47600Y653500D02*
X46500D01*
G01X80300Y639977D02*
X78288Y641989D01*
G01D02*
Y652289D01*
G01D02*
X74477Y656100D01*
G01D02*
X57000D01*
G01D02*
X52600Y660500D01*
G01D02*
X47500D01*
G01X70500Y648500D02*
Y634000D01*
G01X64700Y633430D02*
X48630Y649500D01*
G01D02*
X48000D01*
G01X75000Y636900D02*
Y652607D01*
G01D02*
X74107Y653500D01*
G01D02*
X50560D01*
G01X65500Y927500D02*
Y879185D01*
G01D02*
X72500Y872185D01*
G01X42000Y1054000D02*
X45000Y1057000D01*
G01X58900Y1303500D02*
X80700Y1281700D01*
G01D02*
Y1273240D01*
G01D02*
X91640Y1262300D01*
G01D02*
X212900D01*
G01X100260Y1241800D02*
X171760D01*
G01X148400Y1236000D02*
X100120D01*
G01X173500Y1246000D02*
X102000D01*
G01D02*
X76500Y1271500D01*
G01D02*
Y1279355D01*
G01D02*
X44855Y1311000D01*
G01X172630Y1243900D02*
X101130D01*
G01D02*
X74400Y1270630D01*
G01D02*
Y1278485D01*
G01D02*
X44451Y1308434D01*
G01X100590Y1238500D02*
X172030D01*
G01X45325Y1313500D02*
X78600Y1280225D01*
G01D02*
Y1272370D01*
G01D02*
X102870Y1248100D01*
G01D02*
X174370D01*
G01X58900Y1317000D02*
Y1303500D01*
G01X39779Y1526279D02*
Y1465705D01*
G01X126480Y1525000D02*
X89900D01*
G01D02*
X82308Y1517408D01*
G01D02*
X42960D01*
G01X123870Y1531300D02*
X86740D01*
G01D02*
X82763Y1527323D01*
G01D02*
X47368D01*
G01X124740Y1529200D02*
X88160D01*
G01D02*
X83460Y1524500D01*
G01D02*
X45187D01*
G01D02*
X42644Y1521957D01*
G01X123000Y1533400D02*
X85870D01*
G01D02*
X82570Y1530100D01*
G01D02*
X46570D01*
G01D02*
X43000Y1526530D01*
G01D02*
Y1526000D01*
G01X46893Y1519979D02*
X81909D01*
G01D02*
X89030Y1527100D01*
G01D02*
X125610D01*
G01X77607Y1565391D02*
Y1564107D01*
G01D02*
X39779Y1526279D01*
G01X51635Y1665355D02*
X63760Y1677480D01*
G01D02*
X72980D01*
G01D02*
X79000Y1683500D01*
G01D02*
Y1730015D01*
G01X69500Y1735500D02*
Y1686209D01*
G01D02*
X72500Y1683209D01*
G01X79000Y1730015D02*
X71015Y1738000D01*
G01X67000D02*
X69500Y1735500D01*
G01X167298Y151203D02*
X196403D01*
G01X142900Y220300D02*
Y172475D01*
G01D02*
X154875Y160500D01*
G01X129000Y255500D02*
X134900Y249600D01*
G01D02*
Y228300D01*
G01D02*
X142900Y220300D01*
G01X208000Y278000D02*
X177083Y308917D01*
G01D02*
X171595D01*
G01X158500Y408000D02*
X149000D01*
G01D02*
X143500Y402500D01*
G01X157300Y567900D02*
Y554600D01*
G01D02*
X173200Y538700D01*
G01D02*
Y533900D01*
G01D02*
X237250Y469850D01*
G01X150850Y574350D02*
X157300Y567900D01*
G01X171595Y714429D02*
X208000Y678024D01*
G01X224200Y891800D02*
X167300Y948700D01*
G01D02*
X163800D01*
G01D02*
X161200Y946100D01*
G01X226810Y898100D02*
X169810Y955100D01*
G01D02*
X156800D01*
G01D02*
X155900Y954200D01*
G01X174500Y960000D02*
X205600Y991100D01*
G01X225070Y893900D02*
X168170Y950800D01*
G01D02*
X161700D01*
G01X157200D02*
X159400Y953000D01*
G01D02*
X168940D01*
G01D02*
X225940Y896000D01*
G01X157000Y957500D02*
X170380D01*
G01D02*
X227680Y900200D01*
G01X157000Y995000D02*
Y974000D01*
G01D02*
X174900Y956100D01*
G01D02*
X185700D01*
G01X137500Y1014500D02*
X157000Y995000D01*
G01X205600Y1085936D02*
X171595Y1119941D01*
G01X163170Y1210999D02*
Y1221230D01*
G01X171760Y1241800D02*
X226760Y1186800D01*
G01X163170Y1221230D02*
X148400Y1236000D01*
G01X228500Y1191000D02*
X173500Y1246000D01*
G01X227630Y1188900D02*
X172630Y1243900D01*
G01X172030Y1238500D02*
X226130Y1184400D01*
G01X174370Y1248100D02*
X229370Y1193100D01*
G01X205300Y1322200D02*
X158875Y1368625D01*
G01X167301Y1366838D02*
X190938D01*
G01X158875Y1368625D02*
Y1376100D01*
G01X208000Y1489048D02*
X171595Y1525453D01*
G01X298300Y1538000D02*
X139480D01*
G01D02*
X126480Y1525000D01*
G01X301267Y1547703D02*
X140273D01*
G01D02*
X123870Y1531300D01*
G01X303500Y1542500D02*
X138040D01*
G01D02*
X124740Y1529200D01*
G01X302137Y1549803D02*
X139403D01*
G01D02*
X123000Y1533400D01*
G01X125610Y1527100D02*
X138610Y1540100D01*
G01D02*
X302900D01*
G01X238300Y1715900D02*
X148900D01*
G01D02*
X144400Y1720400D01*
G01X208100Y1718000D02*
X154030D01*
G01D02*
X147630Y1724400D01*
G01X237430Y1713800D02*
X145800D01*
G01D02*
X140300Y1719300D01*
G01D02*
Y1724100D01*
G01X147630Y1724400D02*
X147200D01*
G01X137000Y1727500D02*
X147500D01*
G01D02*
X151200Y1723800D01*
G01D02*
X210930D01*
G01X210059Y1725900D02*
X152070D01*
G01D02*
X148370Y1729600D01*
G01D02*
X141050D01*
G01D02*
X140825Y1729825D01*
G01X209189Y1728000D02*
X152940D01*
G01D02*
X147940Y1733000D01*
G01D02*
X136500D01*
G01X159000Y1954700D02*
Y1823000D01*
G01D02*
X151452Y1815452D01*
G01D02*
Y1810000D01*
G01X208000Y1886700D02*
X171595Y1923105D01*
G01D02*
Y1930965D01*
G01X130025Y1969275D02*
X134900Y1964400D01*
G01D02*
X149300D01*
G01D02*
X159000Y1954700D01*
G01X196403Y151203D02*
X208000Y162800D01*
G01D02*
Y278000D01*
G01X237250Y469850D02*
X355750D01*
G01X208000Y678024D02*
Y576300D01*
G01D02*
X206700Y575000D01*
G01X326500Y891800D02*
X224200D01*
G01X389870Y898100D02*
X226810D01*
G01X382600Y893900D02*
X225070D01*
G01X225940Y896000D02*
X389000D01*
G01X227680Y900200D02*
X390740D01*
G01X205600Y991100D02*
Y1085936D01*
G01X185700Y956100D02*
X198400Y943400D01*
G01D02*
X879600D01*
G01X226760Y1186800D02*
X253260D01*
G01D02*
X289760Y1150300D01*
G01X291500Y1154500D02*
X255000Y1191000D01*
G01D02*
X228500D01*
G01X290630Y1152400D02*
X254130Y1188900D01*
G01D02*
X227630D01*
G01X226130Y1184400D02*
X252690D01*
G01D02*
X286430Y1150660D01*
G01X229370Y1193100D02*
X255870D01*
G01D02*
X291970Y1157000D01*
G01X212900Y1262300D02*
X227400Y1247800D01*
G01D02*
X339400D01*
G01X336765Y1249900D02*
X232300D01*
G01D02*
X205300Y1276900D01*
G01D02*
Y1322200D01*
G01X190938Y1366838D02*
X208000Y1383900D01*
G01D02*
Y1489048D01*
G01X268500Y1708400D02*
X245800D01*
G01D02*
X238300Y1715900D01*
G01X213600Y1723500D02*
X208100Y1718000D01*
G01X267630Y1706300D02*
X244930D01*
G01D02*
X237430Y1713800D01*
G01X257100Y1723500D02*
X213600D01*
G01X210930Y1723800D02*
X212730Y1725600D01*
G01D02*
X256230D01*
G01D02*
X266530Y1735900D01*
G01X265660Y1738000D02*
X255360Y1727700D01*
G01D02*
X211859D01*
G01D02*
X210059Y1725900D01*
G01X264790Y1740100D02*
X254490Y1729800D01*
G01D02*
X210989D01*
G01D02*
X209189Y1728000D01*
G01X203299Y1759750D02*
X205300Y1761751D01*
G01D02*
Y1782400D01*
G01D02*
X208000Y1785100D01*
G01D02*
Y1886700D01*
G01X337593Y880707D02*
X326500Y891800D01*
G01X289760Y1150300D02*
X377000D01*
G01X829000Y1154500D02*
X291500D01*
G01X829870Y1152400D02*
X290630D01*
G01X286430Y1150660D02*
Y1150659D01*
G01D02*
X288889Y1148200D01*
G01D02*
X370580D01*
G01X291970Y1157000D02*
X385700D01*
G01X414300Y1422000D02*
X298300Y1538000D01*
G01X493970Y1355000D02*
X301267Y1547703D01*
G01X493100Y1352900D02*
X303500Y1542500D01*
G01X494740Y1357200D02*
X302137Y1549803D01*
G01X302900Y1540100D02*
X492200Y1350800D01*
G01X376300Y1661000D02*
X326900D01*
G01D02*
X317300Y1670600D01*
G01D02*
X306300D01*
G01D02*
X268500Y1708400D01*
G01X346565Y1658900D02*
X326030D01*
G01D02*
X316430Y1668500D01*
G01D02*
X305430D01*
G01D02*
X267630Y1706300D01*
G01X332265Y1744300D02*
X313157D01*
G01D02*
X302557Y1733700D01*
G01D02*
X267300D01*
G01D02*
X257100Y1723500D01*
G01X266530Y1735900D02*
X300895D01*
G01D02*
X313495Y1748500D01*
G01D02*
X332110D01*
G01X331224Y1750600D02*
X312050D01*
G01D02*
X299450Y1738000D01*
G01D02*
X265660D01*
G01X330354Y1752700D02*
X310341D01*
G01D02*
X297741Y1740100D01*
G01D02*
X264790D01*
G01X355750Y469850D02*
X372590Y453010D01*
G01D02*
X383829D01*
G01D02*
X385607Y451232D01*
G01X385196Y779112D02*
X385562D01*
G01D02*
X401750Y795300D01*
G01D02*
X543000D01*
G01X343894Y880707D02*
X337593D01*
G01X432400Y855570D02*
X389870Y898100D01*
G01X414200Y862300D02*
X382600Y893900D01*
G01X389000Y896000D02*
X430300Y854700D01*
G01X390740Y900200D02*
X434500Y856440D01*
G01X377000Y1150300D02*
X378800Y1148500D01*
G01D02*
X390150D01*
G01D02*
X391900Y1150250D01*
G01X830740Y1150300D02*
X391950D01*
G01D02*
X391900Y1150250D01*
G01X370580Y1148200D02*
X375980Y1142800D01*
G01D02*
X856700D01*
G01X385700Y1157000D02*
X389200Y1160500D01*
G01D02*
X392800D01*
G01D02*
X396300Y1157000D01*
G01D02*
X804250D01*
G01X339400Y1247800D02*
X343822Y1252222D01*
G01X379395Y1252274D02*
X376863Y1254806D01*
G01D02*
X341671D01*
G01D02*
X336765Y1249900D01*
G01X412600Y1684300D02*
X392600Y1664300D01*
G01D02*
X379600D01*
G01D02*
X376300Y1661000D01*
G01X356174Y1649291D02*
X346565Y1658900D01*
G01X343668Y1750741D02*
X338706D01*
G01D02*
X332265Y1744300D01*
G01X332110Y1748500D02*
X337210Y1753600D01*
G01D02*
X358857D01*
G01D02*
X363957Y1748500D01*
G01D02*
X418500D01*
G01X419370Y1750600D02*
X364827D01*
G01D02*
X357594Y1757833D01*
G01D02*
X338457D01*
G01D02*
X331224Y1750600D01*
G01X420240Y1752700D02*
X365697D01*
G01D02*
X358352Y1760045D01*
G01D02*
X337699D01*
G01D02*
X330354Y1752700D01*
G01X539970Y806400D02*
X443130D01*
G01D02*
X432400Y817130D01*
G01D02*
Y855570D01*
G01X420722Y820627D02*
X414200Y827149D01*
G01D02*
Y862300D01*
G01X542130Y797400D02*
X437075D01*
G01D02*
X422976Y811499D01*
G01D02*
Y818373D01*
G01D02*
X420722Y820627D01*
G01X430300Y854700D02*
Y816200D01*
G01D02*
X442200Y804300D01*
G01D02*
X540840D01*
G01X434500Y856440D02*
Y818000D01*
G01D02*
X444000Y808500D01*
G01D02*
X539100D01*
G01X477100Y1249000D02*
X447850Y1219750D01*
G01D02*
X424198D01*
G01D02*
X420763Y1223185D01*
G01D02*
X414300Y1229648D01*
G01D02*
Y1422000D01*
G01X420732Y1721757D02*
X412600Y1713625D01*
G01D02*
Y1684300D01*
G01X422664Y1721757D02*
X424754Y1719667D01*
G01D02*
X438580D01*
G01D02*
X472547Y1685700D01*
G01D02*
X680600D01*
G01X418500Y1748500D02*
X475000Y1692000D01*
G01D02*
X679500D01*
G01X475870Y1694100D02*
X419370Y1750600D01*
G01X476740Y1696200D02*
X420240Y1752700D01*
G01X420732Y1721757D02*
X422664D01*
G01X543000Y795300D02*
X563600Y815900D01*
G01X567171Y833601D02*
X539970Y806400D01*
G01X573830Y829100D02*
X542130Y797400D01*
G01X540840Y804300D02*
X568040Y831500D01*
G01X539100Y808500D02*
X566600Y836000D01*
G01X477100Y1331176D02*
Y1249000D01*
G01X865125Y1346488D02*
X492412D01*
G01D02*
X477100Y1331176D01*
G01X877400Y1355000D02*
X493970D01*
G01X878270Y1352900D02*
X493100D01*
G01X492200Y1350800D02*
X877400D01*
G01X874538Y1357200D02*
X494740D01*
G01X678630Y1694100D02*
X475870D01*
G01X677760Y1696200D02*
X476740D01*
G01X563600Y815900D02*
X752600D01*
G01X786400Y833600D02*
X568910D01*
G01D02*
X568909Y833601D01*
G01D02*
X567171D01*
G01X742370Y829100D02*
X573830D01*
G01X568040Y831500D02*
X785500D01*
G01X566600Y836000D02*
X787000D01*
G01X680600Y1685700D02*
X737300Y1742400D01*
G01X679500Y1692000D02*
X735200Y1747700D01*
G01X734330Y1749800D02*
X678630Y1694100D01*
G01X733460Y1751900D02*
X677760Y1696200D01*
G01X752600Y815900D02*
X818700Y749800D01*
G01X819570Y751900D02*
X742370Y829100D01*
G01X737300Y1742400D02*
X855725D01*
G01X735200Y1747700D02*
X851700D01*
G01X850830Y1749800D02*
X734330D01*
G01X849960Y1751900D02*
X733460D01*
G01X856925Y1969275D02*
X756988D01*
G01D02*
X755995Y1968282D01*
G01X818700Y749800D02*
X854688D01*
G01X855600Y751900D02*
X819570D01*
G01X805983Y781017D02*
X825000Y762000D01*
G01D02*
X856030D01*
G01X808256Y783275D02*
X809756Y784775D01*
G01D02*
Y810244D01*
G01D02*
X786400Y833600D01*
G01X785500Y831500D02*
X805983Y811017D01*
G01D02*
Y781017D01*
G01X787000Y836000D02*
X891500Y731500D01*
G01X869500Y1151800D02*
X832240D01*
G01D02*
X830740Y1150300D01*
G01X868000Y1193500D02*
X829000Y1154500D01*
G01X870100Y1192630D02*
X829870Y1152400D01*
G01X804250Y1157000D02*
X809756Y1162506D01*
G01D02*
Y1186775D01*
G01D02*
X807756Y1188775D01*
G01Y1594275D02*
X874225D01*
G01X923746Y194549D02*
X878072Y148875D01*
G01D02*
X864975D01*
G01X896547Y150803D02*
Y164048D01*
G01D02*
X925846Y193347D01*
G01X906004Y339804D02*
X898041Y331841D01*
G01D02*
Y306459D01*
G01D02*
X923746Y280754D01*
G01X925846Y283012D02*
X899941Y308917D01*
G01X906004Y482296D02*
Y339804D01*
G01X863025Y525275D02*
X906004Y482296D01*
G01X863025Y594825D02*
Y525275D01*
G01X895547Y561548D02*
Y556315D01*
G01X865125Y544000D02*
Y593955D01*
G01X880400Y724088D02*
Y612200D01*
G01D02*
X863025Y594825D01*
G01X924300Y590301D02*
X895547Y561548D01*
G01X865125Y593955D02*
X882500Y611330D01*
G01D02*
Y725000D01*
G01X912000Y584115D02*
X892404Y564519D01*
G01D02*
X888719D01*
G01X886000Y732030D02*
Y670300D01*
G01D02*
X901200Y655100D01*
G01X891500Y731500D02*
Y688500D01*
G01D02*
X912000Y668000D01*
G01X854688Y749800D02*
X880400Y724088D01*
G01X899941Y714429D02*
X924300Y690070D01*
G01X882500Y725000D02*
X855600Y751900D01*
G01X856030Y762000D02*
X886000Y732030D01*
G01X865125Y949600D02*
X882830D01*
G01D02*
X890700Y957470D01*
G01D02*
Y973087D01*
G01D02*
X882300Y981487D01*
G01D02*
Y1139000D01*
G01X911646Y1108236D02*
Y977926D01*
G01D02*
X895547Y961827D01*
G01X877300Y1006600D02*
Y981450D01*
G01D02*
X888719Y970031D01*
G01X879600Y943400D02*
X892800Y956600D01*
G01D02*
Y973957D01*
G01D02*
X884400Y982357D01*
G01D02*
Y1043800D01*
G01X880200Y1132300D02*
Y1009500D01*
G01D02*
X877300Y1006600D01*
G01X884400Y1043800D02*
X901300Y1060700D01*
G01X882300Y1139000D02*
X869500Y1151800D01*
G01X899941Y1119941D02*
X911646Y1108236D01*
G01X856700Y1142800D02*
X863000Y1136500D01*
G01D02*
X876000D01*
G01D02*
X880200Y1132300D01*
G01X868000Y1283000D02*
Y1193500D01*
G01X870100Y1282130D02*
Y1192630D01*
G01X929800Y1344800D02*
X868000Y1283000D01*
G01X931900Y1343930D02*
X870100Y1282130D01*
G01X889539Y1367139D02*
X877400Y1355000D01*
G01X891647Y1366277D02*
X878270Y1352900D01*
G01X886487Y1369149D02*
X874538Y1357200D01*
G01X877400Y1350800D02*
X877401Y1350799D01*
G01D02*
X879139D01*
G01D02*
X893747Y1365407D01*
G01X895647Y1367338D02*
X926300Y1397991D01*
G01X883000Y1447700D02*
Y1404000D01*
G01D02*
X889539Y1397461D01*
G01D02*
Y1367139D01*
G01X915100Y1395000D02*
X891647Y1371547D01*
G01D02*
Y1366277D01*
G01X887438Y1373374D02*
X886487Y1372423D01*
G01D02*
Y1369149D01*
G01X893747Y1365407D02*
Y1369047D01*
G01D02*
X924200Y1399500D01*
G01X901400Y1466100D02*
X883000Y1447700D01*
G01X926300Y1499094D02*
X899941Y1525453D01*
G01X881500Y1587000D02*
Y1537500D01*
G01D02*
X915100Y1503900D01*
G01X924200Y1498000D02*
X897000Y1525200D01*
G01D02*
Y1541500D01*
G01D02*
X926100Y1570600D01*
G01X874225Y1594275D02*
X881500Y1587000D01*
G01X855725Y1742400D02*
X865125Y1751800D01*
G01X851700Y1747700D02*
X862265Y1758265D01*
G01D02*
X876235D01*
G01D02*
X912200Y1794230D01*
G01X914400Y1791703D02*
X895547Y1772850D01*
G01X888719Y1781054D02*
X886365Y1778700D01*
G01D02*
X879730D01*
G01D02*
X850830Y1749800D01*
G01X880516Y1850916D02*
Y1782456D01*
G01D02*
X849960Y1751900D01*
G01X901200Y1871600D02*
X880516Y1850916D01*
G01X912200Y1914800D02*
X893100Y1933900D01*
G01D02*
Y1949000D01*
G01X899941Y1930965D02*
X914400Y1916506D01*
G01X893100Y1949000D02*
X877300Y1964800D01*
G01D02*
X861400D01*
G01D02*
X856925Y1969275D01*
G01X923746Y280754D02*
Y194549D01*
G01X925846Y193347D02*
Y283012D01*
G01X924300Y690070D02*
Y590301D01*
G01X912000Y668000D02*
Y584115D01*
G01X929800Y1637300D02*
Y1344800D01*
G01X931900Y1635389D02*
Y1343930D01*
G01X926300Y1397991D02*
Y1499094D01*
G01X915100Y1503900D02*
Y1395000D01*
G01X924200Y1399500D02*
Y1498000D01*
G01X926100Y1570600D02*
Y1638100D01*
G01X947000Y1654500D02*
X929800Y1637300D01*
G01X943500Y1646989D02*
X931900Y1635389D01*
G01X926100Y1638100D02*
X941000Y1653000D01*
G01X914400Y1916506D02*
Y1791703D01*
G01X912200Y1794230D02*
Y1914800D01*
G01X1045276Y0D02*
X1112953D01*
G03X1127953Y15000I0J15000D01*
G01Y493259D01*
G01X1045276Y25827D02*
G03X1037402I-3937J0D01*
G01X1045276Y0D02*
Y25827D01*
G01X1037402Y56535D02*
G03X1045276I3937J0D01*
G01D02*
Y284882D01*
G01X1037402Y315591D02*
G03X1045276I3937J0D01*
G01Y284882D02*
G03X1037402I-3937J0D01*
G01X1045276Y315591D02*
Y543937D01*
G01D02*
G03X1037402I-3937J0D01*
G01Y574646D02*
G03X1045276I3937J0D01*
G01D02*
Y802992D01*
G01X1037402Y833701D02*
G03X1045276I3937J0D01*
G01Y802992D02*
G03X1037402I-3937J0D01*
G01X1045276Y833701D02*
Y1062047D01*
G01D02*
G03X1037402I-3937J0D01*
G01Y1092756D02*
G03X1045276I3937J0D01*
G01D02*
Y1321102D01*
G01D02*
G03X1037402I-3937J0D01*
G01Y1351811D02*
G03X1045276I3937J0D01*
G01D02*
Y1377638D01*
G01D02*
X1112953D01*
G02X1127953Y1362638I0J-15000D01*
G01Y501133D01*
G01X1045276Y1732598D02*
X1112953D01*
G03X1127953Y1747598I0J15000D01*
G01Y1977126D01*
G03X1112953Y1992126I-15000J0D01*
G01X1045276D01*
G01X1037402Y1767835D02*
G03X1045276I3937J0D01*
G01Y1737126D02*
G03X1037402I-3937J0D01*
G01X1045276Y1767835D02*
Y1956890D01*
G01Y1732598D02*
Y1737126D01*
G01X1037402Y1987598D02*
G03X1045276I3937J0D01*
G01Y1956890D02*
G03X1037402I-3937J0D01*
G01X1045276Y1987598D02*
Y1992126D01*
G01X1127953Y501133D02*
G03Y493259I0J-3937D01*
M02*
